(kicad_pcb
	(version 20260206)
	(generator "pcbnew")
	(generator_version "10.0")
	(general
		(thickness 1.6)
		(legacy_teardrops no)
	)
	(paper "A4")
	(title_block
		(title "01162023_DA0F0TEBIF0_F0T_Expander_BD_F_brd_V02_OCP.brd")
		(comment 1 "Grand Teton / footprints 8280-8285 of 9728")
	)
	(layers
		(0 "F.Cu" signal "TOP")
		(4 "In1.Cu" signal "GND")
		(6 "In2.Cu" signal "VCC")
		(8 "In3.Cu" signal "VCC1")
		(10 "In4.Cu" signal "GND1")
		(12 "In5.Cu" signal "IN1")
		(14 "In6.Cu" signal "GND2")
		(16 "In7.Cu" signal "IN2")
		(18 "In8.Cu" signal "GND3")
		(20 "In9.Cu" signal "IN3")
		(22 "In10.Cu" signal "GND4")
		(24 "In11.Cu" signal "IN4")
		(26 "In12.Cu" signal "GND5")
		(28 "In13.Cu" signal "IN5")
		(30 "In14.Cu" signal "GND6")
		(32 "In15.Cu" signal "IN6")
		(34 "In16.Cu" signal "GND7")
		(2 "B.Cu" signal "BOTTOM")
		(9 "F.Adhes" user "F.Adhesive")
		(11 "B.Adhes" user "B.Adhesive")
		(13 "F.Paste" user "Package Geometry/Pastemask Top")
		(15 "B.Paste" user "Package Geometry/Pastemask Bottom")
		(5 "F.SilkS" user "Ref Des/Silkscreen Top")
		(7 "B.SilkS" user "Ref Des/Silkscreen Bottom")
		(1 "F.Mask" user "Board Geometry/Soldermask Top")
		(3 "B.Mask" user "Board Geometry/Soldermask Bottom")
		(17 "Dwgs.User" user "User.Drawings")
		(19 "Cmts.User" user "User.Comments")
		(21 "Eco1.User" user "User.Eco1")
		(23 "Eco2.User" user "User.Eco2")
		(25 "Edge.Cuts" user "Board Geometry/Outline")
		(27 "Margin" user)
		(31 "F.CrtYd" user "Package Geometry/Place Bound Top")
		(29 "B.CrtYd" user "Package Geometry/Place Bound Bottom")
		(35 "F.Fab" user "Ref Des/Assembly Top")
		(33 "B.Fab" user "Ref Des/Assembly Bottom")
	)
	(footprint ""
		(layer "B.Cu")
		(at 278.326342 -140.8176 180)
		(property "Reference" "C912"
			(at 0 0 0)
			(layer "B.SilkS")
			(hide yes)
			(effects
				(font
					(size 1.27 1.27)
				)
				(justify mirror)
			)
		)
		(property "Value" ""
			(at 0 0 0)
			(layer "B.Fab")
			(effects
				(font
					(size 1.27 1.27)
				)
				(justify mirror)
			)
		)
		(duplicate_pad_numbers_are_jumpers no)
		(fp_line
			(start 0.7874 0.4064)
			(end 0.7874 -0.4064)
			(stroke
				(width 0.1524)
				(type default)
			)
			(layer "B.SilkS")
		)
		(fp_line
			(start 0.7874 -0.4064)
			(end -0.7874 -0.4064)
			(stroke
				(width 0.1524)
				(type default)
			)
			(layer "B.SilkS")
		)
		(fp_line
			(start -0.7874 0.4064)
			(end 0.7874 0.4064)
			(stroke
				(width 0.1524)
				(type default)
			)
			(layer "B.SilkS")
		)
		(fp_line
			(start -0.7874 -0.4064)
			(end -0.7874 0.4064)
			(stroke
				(width 0.1524)
				(type default)
			)
			(layer "B.SilkS")
		)
		(fp_line
			(start 0.67945 0.3048)
			(end 0.67945 -0.305054)
			(stroke
				(width 0.1)
				(type default)
			)
			(layer "B.Fab")
		)
		(fp_line
			(start 0.67945 -0.305054)
			(end 0.12065 -0.305054)
			(stroke
				(width 0.1)
				(type default)
			)
			(layer "B.Fab")
		)
		(fp_line
			(start 0.12065 0.3048)
			(end 0.67945 0.3048)
			(stroke
				(width 0.1)
				(type default)
			)
			(layer "B.Fab")
		)
		(fp_line
			(start 0.12065 0.2794)
			(end 0.12065 0.3048)
			(stroke
				(width 0.1)
				(type default)
			)
			(layer "B.Fab")
		)
		(fp_line
			(start 0.12065 -0.2794)
			(end -0.12065 -0.2794)
			(stroke
				(width 0.1)
				(type default)
			)
			(layer "B.Fab")
		)
		(fp_line
			(start 0.12065 -0.305054)
			(end 0.12065 -0.2794)
			(stroke
				(width 0.1)
				(type default)
			)
			(layer "B.Fab")
		)
		(fp_line
			(start -0.120396 0.3048)
			(end -0.120396 0.2794)
			(stroke
				(width 0.1)
				(type default)
			)
			(layer "B.Fab")
		)
		(fp_line
			(start -0.120396 0.2794)
			(end 0.12065 0.2794)
			(stroke
				(width 0.1)
				(type default)
			)
			(layer "B.Fab")
		)
		(fp_line
			(start -0.12065 -0.2794)
			(end -0.12065 -0.3048)
			(stroke
				(width 0.1)
				(type default)
			)
			(layer "B.Fab")
		)
		(fp_line
			(start -0.12065 -0.3048)
			(end -0.67945 -0.3048)
			(stroke
				(width 0.1)
				(type default)
			)
			(layer "B.Fab")
		)
		(fp_line
			(start -0.67945 0.3048)
			(end -0.120396 0.3048)
			(stroke
				(width 0.1)
				(type default)
			)
			(layer "B.Fab")
		)
		(fp_line
			(start -0.67945 -0.3048)
			(end -0.67945 0.3048)
			(stroke
				(width 0.1)
				(type default)
			)
			(layer "B.Fab")
		)
		(pad "1" smd circle
			(at 0.40005 0)
			(size 0 0)
			(layers "B.Cu" "B.Mask" "B.Paste")
			(net "P3V3_NIC4")
		)
		(pad "2" smd circle
			(at -0.40005 0)
			(size 0 0)
			(layers "B.Cu" "B.Mask" "B.Paste")
			(net "GND")
		)
	)
	(footprint ""
		(layer "B.Cu")
		(at 293.27475 -297.79976 -90)
		(property "Reference" "C1649"
			(at 0 0 90)
			(layer "B.SilkS")
			(hide yes)
			(effects
				(font
					(size 1.27 1.27)
				)
				(justify mirror)
			)
		)
		(property "Value" ""
			(at 0 0 90)
			(layer "B.Fab")
			(effects
				(font
					(size 1.27 1.27)
				)
				(justify mirror)
			)
		)
		(duplicate_pad_numbers_are_jumpers no)
		(fp_line
			(start -0.299974 0.150114)
			(end 0.299974 0.150114)
			(stroke
				(width 0.1)
				(type default)
			)
			(layer "B.Fab")
		)
		(fp_line
			(start 0.299974 0.150114)
			(end 0.299974 -0.150114)
			(stroke
				(width 0.1)
				(type default)
			)
			(layer "B.Fab")
		)
		(fp_line
			(start -0.299974 -0.150114)
			(end -0.299974 0.150114)
			(stroke
				(width 0.1)
				(type default)
			)
			(layer "B.Fab")
		)
		(fp_line
			(start 0.299974 -0.150114)
			(end -0.299974 -0.150114)
			(stroke
				(width 0.1)
				(type default)
			)
			(layer "B.Fab")
		)
		(pad "1" smd rect
			(at 0.2667 0 90)
			(size 0.3048 0.381)
			(layers "B.Cu" "B.Mask" "B.Paste")
			(net "P0V8_PEX2")
		)
		(pad "2" smd rect
			(at -0.2667 0 90)
			(size 0.3048 0.381)
			(layers "B.Cu" "B.Mask" "B.Paste")
			(net "GND")
		)
	)
	(footprint ""
		(layer "B.Cu")
		(at 414.376616 -111.334042 180)
		(property "Reference" "R393"
			(at 0 0 0)
			(layer "B.SilkS")
			(hide yes)
			(effects
				(font
					(size 1.27 1.27)
				)
				(justify mirror)
			)
		)
		(property "Value" ""
			(at 0 0 0)
			(layer "B.Fab")
			(effects
				(font
					(size 1.27 1.27)
				)
				(justify mirror)
			)
		)
		(duplicate_pad_numbers_are_jumpers no)
		(fp_line
			(start 0.7874 0.4064)
			(end 0.7874 -0.4064)
			(stroke
				(width 0.1524)
				(type default)
			)
			(layer "B.SilkS")
		)
		(fp_line
			(start 0.7874 -0.4064)
			(end -0.7874 -0.4064)
			(stroke
				(width 0.1524)
				(type default)
			)
			(layer "B.SilkS")
		)
		(fp_line
			(start -0.7874 0.4064)
			(end 0.7874 0.4064)
			(stroke
				(width 0.1524)
				(type default)
			)
			(layer "B.SilkS")
		)
		(fp_line
			(start -0.7874 -0.4064)
			(end -0.7874 0.4064)
			(stroke
				(width 0.1524)
				(type default)
			)
			(layer "B.SilkS")
		)
		(fp_line
			(start 0.67945 0.3048)
			(end 0.67945 -0.305054)
			(stroke
				(width 0.1)
				(type default)
			)
			(layer "B.Fab")
		)
		(fp_line
			(start 0.67945 -0.305054)
			(end 0.12065 -0.305054)
			(stroke
				(width 0.1)
				(type default)
			)
			(layer "B.Fab")
		)
		(fp_line
			(start 0.12065 0.3048)
			(end 0.67945 0.3048)
			(stroke
				(width 0.1)
				(type default)
			)
			(layer "B.Fab")
		)
		(fp_line
			(start 0.12065 0.2794)
			(end 0.12065 0.3048)
			(stroke
				(width 0.1)
				(type default)
			)
			(layer "B.Fab")
		)
		(fp_line
			(start 0.12065 -0.2794)
			(end -0.12065 -0.2794)
			(stroke
				(width 0.1)
				(type default)
			)
			(layer "B.Fab")
		)
		(fp_line
			(start 0.12065 -0.305054)
			(end 0.12065 -0.2794)
			(stroke
				(width 0.1)
				(type default)
			)
			(layer "B.Fab")
		)
		(fp_line
			(start -0.120396 0.3048)
			(end -0.120396 0.2794)
			(stroke
				(width 0.1)
				(type default)
			)
			(layer "B.Fab")
		)
		(fp_line
			(start -0.120396 0.2794)
			(end 0.12065 0.2794)
			(stroke
				(width 0.1)
				(type default)
			)
			(layer "B.Fab")
		)
		(fp_line
			(start -0.12065 -0.2794)
			(end -0.12065 -0.3048)
			(stroke
				(width 0.1)
				(type default)
			)
			(layer "B.Fab")
		)
		(fp_line
			(start -0.12065 -0.3048)
			(end -0.67945 -0.3048)
			(stroke
				(width 0.1)
				(type default)
			)
			(layer "B.Fab")
		)
		(fp_line
			(start -0.67945 0.3048)
			(end -0.120396 0.3048)
			(stroke
				(width 0.1)
				(type default)
			)
			(layer "B.Fab")
		)
		(fp_line
			(start -0.67945 -0.3048)
			(end -0.67945 0.3048)
			(stroke
				(width 0.1)
				(type default)
			)
			(layer "B.Fab")
		)
		(pad "1" smd circle
			(at 0.40005 0)
			(size 0 0)
			(layers "B.Cu" "B.Mask" "B.Paste")
			(net "RST_SMB_NIC_MUX_R_N")
		)
		(pad "2" smd circle
			(at -0.40005 0)
			(size 0 0)
			(layers "B.Cu" "B.Mask" "B.Paste")
			(net "RST_SMB_NIC7_MUX_N")
		)
	)
	(footprint ""
		(layer "B.Cu")
		(at 49.5554 -157.0736 180)
		(property "Reference" "R1"
			(at 0 0 0)
			(layer "B.SilkS")
			(hide yes)
			(effects
				(font
					(size 1.27 1.27)
				)
				(justify mirror)
			)
		)
		(property "Value" ""
			(at 0 0 0)
			(layer "B.Fab")
			(effects
				(font
					(size 1.27 1.27)
				)
				(justify mirror)
			)
		)
		(duplicate_pad_numbers_are_jumpers no)
		(fp_line
			(start 0.7874 0.4064)
			(end 0.7874 -0.4064)
			(stroke
				(width 0.1524)
				(type default)
			)
			(layer "B.SilkS")
		)
		(fp_line
			(start 0.7874 -0.4064)
			(end -0.7874 -0.4064)
			(stroke
				(width 0.1524)
				(type default)
			)
			(layer "B.SilkS")
		)
		(fp_line
			(start -0.7874 0.4064)
			(end 0.7874 0.4064)
			(stroke
				(width 0.1524)
				(type default)
			)
			(layer "B.SilkS")
		)
		(fp_line
			(start -0.7874 -0.4064)
			(end -0.7874 0.4064)
			(stroke
				(width 0.1524)
				(type default)
			)
			(layer "B.SilkS")
		)
		(fp_line
			(start 0.67945 0.3048)
			(end 0.67945 -0.305054)
			(stroke
				(width 0.1)
				(type default)
			)
			(layer "B.Fab")
		)
		(fp_line
			(start 0.67945 -0.305054)
			(end 0.12065 -0.305054)
			(stroke
				(width 0.1)
				(type default)
			)
			(layer "B.Fab")
		)
		(fp_line
			(start 0.12065 0.3048)
			(end 0.67945 0.3048)
			(stroke
				(width 0.1)
				(type default)
			)
			(layer "B.Fab")
		)
		(fp_line
			(start 0.12065 0.2794)
			(end 0.12065 0.3048)
			(stroke
				(width 0.1)
				(type default)
			)
			(layer "B.Fab")
		)
		(fp_line
			(start 0.12065 -0.2794)
			(end -0.12065 -0.2794)
			(stroke
				(width 0.1)
				(type default)
			)
			(layer "B.Fab")
		)
		(fp_line
			(start 0.12065 -0.305054)
			(end 0.12065 -0.2794)
			(stroke
				(width 0.1)
				(type default)
			)
			(layer "B.Fab")
		)
		(fp_line
			(start -0.120396 0.3048)
			(end -0.120396 0.2794)
			(stroke
				(width 0.1)
				(type default)
			)
			(layer "B.Fab")
		)
		(fp_line
			(start -0.120396 0.2794)
			(end 0.12065 0.2794)
			(stroke
				(width 0.1)
				(type default)
			)
			(layer "B.Fab")
		)
		(fp_line
			(start -0.12065 -0.2794)
			(end -0.12065 -0.3048)
			(stroke
				(width 0.1)
				(type default)
			)
			(layer "B.Fab")
		)
		(fp_line
			(start -0.12065 -0.3048)
			(end -0.67945 -0.3048)
			(stroke
				(width 0.1)
				(type default)
			)
			(layer "B.Fab")
		)
		(fp_line
			(start -0.67945 0.3048)
			(end -0.120396 0.3048)
			(stroke
				(width 0.1)
				(type default)
			)
			(layer "B.Fab")
		)
		(fp_line
			(start -0.67945 -0.3048)
			(end -0.67945 0.3048)
			(stroke
				(width 0.1)
				(type default)
			)
			(layer "B.Fab")
		)
		(pad "1" smd circle
			(at 0.40005 0)
			(size 0 0)
			(layers "B.Cu" "B.Mask" "B.Paste")
			(net "NIC0_RBT_ARB_OUT")
		)
		(pad "2" smd circle
			(at -0.40005 0)
			(size 0 0)
			(layers "B.Cu" "B.Mask" "B.Paste")
			(net "NIC0_RBT_ARB_IN")
		)
	)
	(footprint ""
		(layer "B.Cu")
		(at 302.061626 -239.976406 90)
		(property "Reference" "R4108"
			(at 0 0 90)
			(layer "B.SilkS")
			(hide yes)
			(effects
				(font
					(size 1.27 1.27)
				)
				(justify mirror)
			)
		)
		(property "Value" ""
			(at 0 0 90)
			(layer "B.Fab")
			(effects
				(font
					(size 1.27 1.27)
				)
				(justify mirror)
			)
		)
		(duplicate_pad_numbers_are_jumpers no)
		(fp_line
			(start 0.7874 -0.4064)
			(end -0.7874 -0.4064)
			(stroke
				(width 0.1524)
				(type default)
			)
			(layer "B.SilkS")
		)
		(fp_line
			(start -0.7874 -0.4064)
			(end -0.7874 0.4064)
			(stroke
				(width 0.1524)
				(type default)
			)
			(layer "B.SilkS")
		)
		(fp_line
			(start 0.7874 0.4064)
			(end 0.7874 -0.4064)
			(stroke
				(width 0.1524)
				(type default)
			)
			(layer "B.SilkS")
		)
		(fp_line
			(start -0.7874 0.4064)
			(end 0.7874 0.4064)
			(stroke
				(width 0.1524)
				(type default)
			)
			(layer "B.SilkS")
		)
		(fp_line
			(start 0.67945 -0.305054)
			(end 0.12065 -0.305054)
			(stroke
				(width 0.1)
				(type default)
			)
			(layer "B.Fab")
		)
		(fp_line
			(start 0.12065 -0.305054)
			(end 0.12065 -0.2794)
			(stroke
				(width 0.1)
				(type default)
			)
			(layer "B.Fab")
		)
		(fp_line
			(start -0.12065 -0.3048)
			(end -0.67945 -0.3048)
			(stroke
				(width 0.1)
				(type default)
			)
			(layer "B.Fab")
		)
		(fp_line
			(start -0.67945 -0.3048)
			(end -0.67945 0.3048)
			(stroke
				(width 0.1)
				(type default)
			)
			(layer "B.Fab")
		)
		(fp_line
			(start 0.12065 -0.2794)
			(end -0.12065 -0.2794)
			(stroke
				(width 0.1)
				(type default)
			)
			(layer "B.Fab")
		)
		(fp_line
			(start -0.12065 -0.2794)
			(end -0.12065 -0.3048)
			(stroke
				(width 0.1)
				(type default)
			)
			(layer "B.Fab")
		)
		(fp_line
			(start 0.12065 0.2794)
			(end 0.12065 0.3048)
			(stroke
				(width 0.1)
				(type default)
			)
			(layer "B.Fab")
		)
		(fp_line
			(start -0.120396 0.2794)
			(end 0.12065 0.2794)
			(stroke
				(width 0.1)
				(type default)
			)
			(layer "B.Fab")
		)
		(fp_line
			(start 0.67945 0.3048)
			(end 0.67945 -0.305054)
			(stroke
				(width 0.1)
				(type default)
			)
			(layer "B.Fab")
		)
		(fp_line
			(start 0.12065 0.3048)
			(end 0.67945 0.3048)
			(stroke
				(width 0.1)
				(type default)
			)
			(layer "B.Fab")
		)
		(fp_line
			(start -0.120396 0.3048)
			(end -0.120396 0.2794)
			(stroke
				(width 0.1)
				(type default)
			)
			(layer "B.Fab")
		)
		(fp_line
			(start -0.67945 0.3048)
			(end -0.120396 0.3048)
			(stroke
				(width 0.1)
				(type default)
			)
			(layer "B.Fab")
		)
		(pad "1" smd circle
			(at 0.40005 0 270)
			(size 0 0)
			(layers "B.Cu" "B.Mask" "B.Paste")
			(net "SMB_MB_BMC_ISO_SDA")
		)
		(pad "2" smd circle
			(at -0.40005 0 270)
			(size 0 0)
			(layers "B.Cu" "B.Mask" "B.Paste")
			(net "SMB_MB_R_SDA")
		)
	)
	(footprint ""
		(layer "B.Cu")
		(at 355.300788 -293.660068 90)
		(property "Reference" "PC200"
			(at 0 0 90)
			(layer "B.SilkS")
			(hide yes)
			(effects
				(font
					(size 1.27 1.27)
				)
				(justify mirror)
			)
		)
		(property "Value" ""
			(at 0 0 90)
			(layer "B.Fab")
			(effects
				(font
					(size 1.27 1.27)
				)
				(justify mirror)
			)
		)
		(duplicate_pad_numbers_are_jumpers no)
		(fp_line
			(start 4.84378 -2.150618)
			(end 4.53898 -2.150618)
			(stroke
				(width 0.1524)
				(type default)
			)
			(layer "B.SilkS")
		)
		(fp_line
			(start 4.84378 -2.150618)
			(end 4.842256 2.163064)
			(stroke
				(width 0.1524)
				(type default)
			)
			(layer "B.SilkS")
		)
		(fp_line
			(start 4.69138 -2.150618)
			(end 4.692396 2.161032)
			(stroke
				(width 0.1524)
				(type default)
			)
			(layer "B.SilkS")
		)
		(fp_line
			(start 4.53898 -2.150618)
			(end 4.539742 2.152142)
			(stroke
				(width 0.1524)
				(type default)
			)
			(layer "B.SilkS")
		)
		(fp_line
			(start 4.53898 -2.15011)
			(end -4.53898 -2.15011)
			(stroke
				(width 0.1524)
				(type default)
			)
			(layer "B.SilkS")
		)
		(fp_line
			(start -4.53898 -2.15011)
			(end -4.53898 2.15011)
			(stroke
				(width 0.1524)
				(type default)
			)
			(layer "B.SilkS")
		)
		(fp_line
			(start 4.53898 2.15011)
			(end 4.53898 -2.15011)
			(stroke
				(width 0.1524)
				(type default)
			)
			(layer "B.SilkS")
		)
		(fp_line
			(start -4.53898 2.15011)
			(end 4.53898 2.15011)
			(stroke
				(width 0.1524)
				(type default)
			)
			(layer "B.SilkS")
		)
		(fp_line
			(start 4.83108 2.150364)
			(end 4.447794 2.149348)
			(stroke
				(width 0.1524)
				(type default)
			)
			(layer "B.SilkS")
		)
		(fp_line
			(start 3.64998 -2.15011)
			(end -3.64998 -2.15011)
			(stroke
				(width 0.1)
				(type default)
			)
			(layer "B.Fab")
		)
		(fp_line
			(start -3.64998 -2.15011)
			(end -3.64998 2.15011)
			(stroke
				(width 0.1)
				(type default)
			)
			(layer "B.Fab")
		)
		(fp_line
			(start 3.64998 2.15011)
			(end 3.64998 -2.15011)
			(stroke
				(width 0.1)
				(type default)
			)
			(layer "B.Fab")
		)
		(fp_line
			(start -3.64998 2.15011)
			(end 3.64998 2.15011)
			(stroke
				(width 0.1)
				(type default)
			)
			(layer "B.Fab")
		)
		(fp_text user "+"
			(at 6.214872 -0.337058 90)
			(unlocked yes)
			(layer "B.SilkS")
			(effects
				(font
					(size 1.905 1.4224)
					(thickness 0.1524)
				)
				(justify left mirror)
			)
		)
		(fp_text user "-"
			(at -4.313174 -0.094488 90)
			(unlocked yes)
			(layer "B.SilkS")
			(effects
				(font
					(size 1.905 1.4224)
					(thickness 0.1524)
				)
				(justify left mirror)
			)
		)
		(fp_text user "+"
			(at 6.214872 -0.337058 90)
			(unlocked yes)
			(layer "B.Fab")
			(effects
				(font
					(size 1.905 1.4224)
					(thickness 0.1524)
				)
				(justify left mirror)
			)
		)
		(fp_text user "-"
			(at -4.313174 -0.094488 90)
			(unlocked yes)
			(layer "B.Fab")
			(effects
				(font
					(size 1.905 1.4224)
					(thickness 0.1524)
				)
				(justify left mirror)
			)
		)
		(pad "1" smd rect
			(at 3.199892 0 270)
			(size 2.413 2.8194)
			(layers "B.Cu" "B.Mask" "B.Paste")
			(net "P0V8_PEX3")
		)
		(pad "2" smd rect
			(at -3.199892 0 270)
			(size 2.413 2.8194)
			(layers "B.Cu" "B.Mask" "B.Paste")
			(net "GND")
		)
	)
)
